# T6G (Grand Teton) — schematic netlist excerpt (pin names and nets, part order shuffled) for the footprints in the layout excerpt that follows; sources: Cadence DE-HDL packaged netlist, KiCad conversion of 04192023_DAF0TMB3IC0_F0TG_MB_C_brd_V02_OCP.brd

R176  Q_RES  33 5% CHIP  pkg 0402LF  page 81 : A = PVDD18_S5_P0_EN ; B = FM_PVDD18_S5_P0_EN
R3612  Q_RES  4.7K 1% EMPTY  pkg 0402LF  page 237 : A = GND ; B = INA230_5_A1

(kicad_pcb
	(version 20260206)
	(generator "pcbnew")
	(generator_version "10.0")
	(general
		(thickness 1.6)
		(legacy_teardrops no)
	)
	(paper "A4")
	(title_block
		(title "04192023_DAF0TMB3IC0_F0TG_MB_C_brd_V02_OCP.brd")
		(comment 1 "Grand Teton / footprints 345-346 of 8354")
	)
	(layers
		(0 "F.Cu" signal "TOP")
		(4 "In1.Cu" signal "GND")
		(6 "In2.Cu" signal "IN1")
		(8 "In3.Cu" signal "GND1")
		(10 "In4.Cu" signal "IN2")
		(12 "In5.Cu" signal "GND2")
		(14 "In6.Cu" signal "IN3")
		(16 "In7.Cu" signal "GND3")
		(18 "In8.Cu" signal "VCC")
		(20 "In9.Cu" signal "VCC1")
		(22 "In10.Cu" signal "GND4")
		(24 "In11.Cu" signal "IN4")
		(26 "In12.Cu" signal "GND5")
		(28 "In13.Cu" signal "IN5")
		(30 "In14.Cu" signal "GND6")
		(32 "In15.Cu" signal "IN6")
		(34 "In16.Cu" signal "GND7")
		(2 "B.Cu" signal "BOTTOM")
		(9 "F.Adhes" user "F.Adhesive")
		(11 "B.Adhes" user "B.Adhesive")
		(13 "F.Paste" user "Package Geometry/Pastemask Top")
		(15 "B.Paste" user "Package Geometry/Pastemask Bottom")
		(5 "F.SilkS" user "Ref Des/Silkscreen Top")
		(7 "B.SilkS" user "Ref Des/Silkscreen Bottom")
		(1 "F.Mask" user "Board Geometry/Soldermask Top")
		(3 "B.Mask" user "Board Geometry/Soldermask Bottom")
		(17 "Dwgs.User" user "User.Drawings")
		(19 "Cmts.User" user "User.Comments")
		(21 "Eco1.User" user "User.Eco1")
		(23 "Eco2.User" user "User.Eco2")
		(25 "Edge.Cuts" user "Board Geometry/Outline")
		(27 "Margin" user)
		(31 "F.CrtYd" user "Package Geometry/Place Bound Top")
		(29 "B.CrtYd" user "Package Geometry/Place Bound Bottom")
		(35 "F.Fab" user "Ref Des/Assembly Top")
		(33 "B.Fab" user "Ref Des/Assembly Bottom")
	)
	(footprint ""
		(layer "F.Cu")
		(at 197.269608 -110.577376 180)
		(property "Reference" "R176"
			(at 0 0 180)
			(layer "F.SilkS")
			(hide yes)
			(effects
				(font
					(size 1.27 1.27)
				)
			)
		)
		(property "Value" ""
			(at 0 0 180)
			(layer "F.Fab")
			(effects
				(font
					(size 1.27 1.27)
				)
			)
		)
		(duplicate_pad_numbers_are_jumpers no)
		(fp_line
			(start 0.7874 0.4064)
			(end -0.7874 0.4064)
			(stroke
				(width 0.1524)
				(type default)
			)
			(layer "F.SilkS")
		)
		(fp_line
			(start 0.7874 -0.4064)
			(end 0.7874 0.4064)
			(stroke
				(width 0.1524)
				(type default)
			)
			(layer "F.SilkS")
		)
		(fp_line
			(start -0.7874 0.4064)
			(end -0.7874 -0.4064)
			(stroke
				(width 0.1524)
				(type default)
			)
			(layer "F.SilkS")
		)
		(fp_line
			(start -0.7874 -0.4064)
			(end 0.7874 -0.4064)
			(stroke
				(width 0.1524)
				(type default)
			)
			(layer "F.SilkS")
		)
		(fp_line
			(start 0.67945 0.3048)
			(end 0.120396 0.3048)
			(stroke
				(width 0.1)
				(type default)
			)
			(layer "F.Fab")
		)
		(fp_line
			(start 0.67945 -0.3048)
			(end 0.67945 0.3048)
			(stroke
				(width 0.1)
				(type default)
			)
			(layer "F.Fab")
		)
		(fp_line
			(start 0.12065 -0.2794)
			(end 0.12065 -0.3048)
			(stroke
				(width 0.1)
				(type default)
			)
			(layer "F.Fab")
		)
		(fp_line
			(start 0.12065 -0.3048)
			(end 0.67945 -0.3048)
			(stroke
				(width 0.1)
				(type default)
			)
			(layer "F.Fab")
		)
		(fp_line
			(start 0.120396 0.3048)
			(end 0.120396 0.2794)
			(stroke
				(width 0.1)
				(type default)
			)
			(layer "F.Fab")
		)
		(fp_line
			(start 0.120396 0.2794)
			(end -0.12065 0.2794)
			(stroke
				(width 0.1)
				(type default)
			)
			(layer "F.Fab")
		)
		(fp_line
			(start -0.12065 0.3048)
			(end -0.67945 0.3048)
			(stroke
				(width 0.1)
				(type default)
			)
			(layer "F.Fab")
		)
		(fp_line
			(start -0.12065 0.2794)
			(end -0.12065 0.3048)
			(stroke
				(width 0.1)
				(type default)
			)
			(layer "F.Fab")
		)
		(fp_line
			(start -0.12065 -0.2794)
			(end 0.12065 -0.2794)
			(stroke
				(width 0.1)
				(type default)
			)
			(layer "F.Fab")
		)
		(fp_line
			(start -0.12065 -0.305054)
			(end -0.12065 -0.2794)
			(stroke
				(width 0.1)
				(type default)
			)
			(layer "F.Fab")
		)
		(fp_line
			(start -0.67945 0.3048)
			(end -0.67945 -0.305054)
			(stroke
				(width 0.1)
				(type default)
			)
			(layer "F.Fab")
		)
		(fp_line
			(start -0.67945 -0.305054)
			(end -0.12065 -0.305054)
			(stroke
				(width 0.1)
				(type default)
			)
			(layer "F.Fab")
		)
		(pad "1" smd circle
			(at -0.40005 0 180)
			(size 0 0)
			(layers "F.Cu" "F.Mask" "F.Paste")
			(net "PVDD18_S5_P0_EN")
		)
		(pad "2" smd circle
			(at 0.40005 0 180)
			(size 0 0)
			(layers "F.Cu" "F.Mask" "F.Paste")
			(net "FM_PVDD18_S5_P0_EN")
		)
	)
	(footprint ""
		(layer "F.Cu")
		(at 208.054956 -30.276292 90)
		(property "Reference" "R3612"
			(at 0 0 90)
			(layer "F.SilkS")
			(hide yes)
			(effects
				(font
					(size 1.27 1.27)
				)
			)
		)
		(property "Value" ""
			(at 0 0 90)
			(layer "F.Fab")
			(effects
				(font
					(size 1.27 1.27)
				)
			)
		)
		(duplicate_pad_numbers_are_jumpers no)
		(fp_line
			(start 0.7874 -0.4064)
			(end 0.7874 0.4064)
			(stroke
				(width 0.1524)
				(type default)
			)
			(layer "F.SilkS")
		)
		(fp_line
			(start -0.7874 -0.4064)
			(end 0.7874 -0.4064)
			(stroke
				(width 0.1524)
				(type default)
			)
			(layer "F.SilkS")
		)
		(fp_line
			(start 0.7874 0.4064)
			(end -0.7874 0.4064)
			(stroke
				(width 0.1524)
				(type default)
			)
			(layer "F.SilkS")
		)
		(fp_line
			(start -0.7874 0.4064)
			(end -0.7874 -0.4064)
			(stroke
				(width 0.1524)
				(type default)
			)
			(layer "F.SilkS")
		)
		(fp_line
			(start -0.12065 -0.305054)
			(end -0.12065 -0.2794)
			(stroke
				(width 0.1)
				(type default)
			)
			(layer "F.Fab")
		)
		(fp_line
			(start -0.67945 -0.305054)
			(end -0.12065 -0.305054)
			(stroke
				(width 0.1)
				(type default)
			)
			(layer "F.Fab")
		)
		(fp_line
			(start 0.67945 -0.3048)
			(end 0.67945 0.3048)
			(stroke
				(width 0.1)
				(type default)
			)
			(layer "F.Fab")
		)
		(fp_line
			(start 0.12065 -0.3048)
			(end 0.67945 -0.3048)
			(stroke
				(width 0.1)
				(type default)
			)
			(layer "F.Fab")
		)
		(fp_line
			(start 0.12065 -0.2794)
			(end 0.12065 -0.3048)
			(stroke
				(width 0.1)
				(type default)
			)
			(layer "F.Fab")
		)
		(fp_line
			(start -0.12065 -0.2794)
			(end 0.12065 -0.2794)
			(stroke
				(width 0.1)
				(type default)
			)
			(layer "F.Fab")
		)
		(fp_line
			(start 0.120396 0.2794)
			(end -0.12065 0.2794)
			(stroke
				(width 0.1)
				(type default)
			)
			(layer "F.Fab")
		)
		(fp_line
			(start -0.12065 0.2794)
			(end -0.12065 0.3048)
			(stroke
				(width 0.1)
				(type default)
			)
			(layer "F.Fab")
		)
		(fp_line
			(start 0.67945 0.3048)
			(end 0.120396 0.3048)
			(stroke
				(width 0.1)
				(type default)
			)
			(layer "F.Fab")
		)
		(fp_line
			(start 0.120396 0.3048)
			(end 0.120396 0.2794)
			(stroke
				(width 0.1)
				(type default)
			)
			(layer "F.Fab")
		)
		(fp_line
			(start -0.12065 0.3048)
			(end -0.67945 0.3048)
			(stroke
				(width 0.1)
				(type default)
			)
			(layer "F.Fab")
		)
		(fp_line
			(start -0.67945 0.3048)
			(end -0.67945 -0.305054)
			(stroke
				(width 0.1)
				(type default)
			)
			(layer "F.Fab")
		)
		(pad "1" smd circle
			(at -0.40005 0 90)
			(size 0 0)
			(layers "F.Cu" "F.Mask" "F.Paste")
			(net "GND")
		)
		(pad "2" smd circle
			(at 0.40005 0 90)
			(size 0 0)
			(layers "F.Cu" "F.Mask" "F.Paste")
			(net "INA230_5_A1")
		)
	)
)
